(kicad_pcb
	(version 20260206)
	(generator "pcbnew")
	(generator_version "10.0")
	(general
		(thickness 1.6)
		(legacy_teardrops no)
	)
	(paper "A4")
	(title_block
		(title "03242023_DA0F0TMBIJ0_F0T_Motherboard_J_brd_V01_OCP.brd")
		(comment 1 "Grand Teton / footprints 4229-4234 of 6105")
	)
	(layers
		(0 "F.Cu" signal "TOP")
		(4 "In1.Cu" signal "GND")
		(6 "In2.Cu" signal "IN1")
		(8 "In3.Cu" signal "GND1")
		(10 "In4.Cu" signal "IN2")
		(12 "In5.Cu" signal "GND2")
		(14 "In6.Cu" signal "IN3")
		(16 "In7.Cu" signal "GND3")
		(18 "In8.Cu" signal "VCC")
		(20 "In9.Cu" signal "VCC1")
		(22 "In10.Cu" signal "GND4")
		(24 "In11.Cu" signal "IN4")
		(26 "In12.Cu" signal "GND5")
		(28 "In13.Cu" signal "IN5")
		(30 "In14.Cu" signal "GND6")
		(32 "In15.Cu" signal "IN6")
		(34 "In16.Cu" signal "GND7")
		(2 "B.Cu" signal "BOTTOM")
		(9 "F.Adhes" user "F.Adhesive")
		(11 "B.Adhes" user "B.Adhesive")
		(13 "F.Paste" user "Package Geometry/Pastemask Top")
		(15 "B.Paste" user "Package Geometry/Pastemask Bottom")
		(5 "F.SilkS" user "Ref Des/Silkscreen Top")
		(7 "B.SilkS" user "Ref Des/Silkscreen Bottom")
		(1 "F.Mask" user "Board Geometry/Soldermask Top")
		(3 "B.Mask" user "Board Geometry/Soldermask Bottom")
		(17 "Dwgs.User" user "User.Drawings")
		(19 "Cmts.User" user "User.Comments")
		(21 "Eco1.User" user "User.Eco1")
		(23 "Eco2.User" user "User.Eco2")
		(25 "Edge.Cuts" user "Board Geometry/Outline")
		(27 "Margin" user)
		(31 "F.CrtYd" user "Package Geometry/Place Bound Top")
		(29 "B.CrtYd" user "Package Geometry/Place Bound Bottom")
		(35 "F.Fab" user "Ref Des/Assembly Top")
		(33 "B.Fab" user "Ref Des/Assembly Bottom")
	)
	(footprint ""
		(layer "B.Cu")
		(at 60.959746 -321.554856 -90)
		(property "Reference" "C55"
			(at 0 0 90)
			(layer "B.SilkS")
			(hide yes)
			(effects
				(font
					(size 1.27 1.27)
				)
				(justify mirror)
			)
		)
		(property "Value" ""
			(at 0 0 90)
			(layer "B.Fab")
			(effects
				(font
					(size 1.27 1.27)
				)
				(justify mirror)
			)
		)
		(duplicate_pad_numbers_are_jumpers no)
		(fp_line
			(start -1.524 0.762)
			(end 1.524 0.762)
			(stroke
				(width 0.1524)
				(type default)
			)
			(layer "B.SilkS")
		)
		(fp_line
			(start 1.524 0.762)
			(end 1.524 -0.762)
			(stroke
				(width 0.1524)
				(type default)
			)
			(layer "B.SilkS")
		)
		(fp_line
			(start -1.524 -0.762)
			(end -1.524 0.762)
			(stroke
				(width 0.1524)
				(type default)
			)
			(layer "B.SilkS")
		)
		(fp_line
			(start 1.524 -0.762)
			(end -1.524 -0.762)
			(stroke
				(width 0.1524)
				(type default)
			)
			(layer "B.SilkS")
		)
		(fp_line
			(start -1.1049 0.724916)
			(end -1.1049 -0.724916)
			(stroke
				(width 0.1)
				(type default)
			)
			(layer "B.Fab")
		)
		(fp_line
			(start 1.1049 0.724916)
			(end -1.1049 0.724916)
			(stroke
				(width 0.1)
				(type default)
			)
			(layer "B.Fab")
		)
		(fp_line
			(start -1.1049 -0.724916)
			(end 1.1049 -0.724916)
			(stroke
				(width 0.1)
				(type default)
			)
			(layer "B.Fab")
		)
		(fp_line
			(start 1.1049 -0.724916)
			(end 1.1049 0.724916)
			(stroke
				(width 0.1)
				(type default)
			)
			(layer "B.Fab")
		)
		(pad "1" smd rect
			(at 0.889 0 270)
			(size 1.016 1.27)
			(layers "B.Cu" "B.Mask" "B.Paste")
			(net "P12V_S3_AUX_CPU1_NVDIMM")
		)
		(pad "2" smd rect
			(at -0.889 0 270)
			(size 1.016 1.27)
			(layers "B.Cu" "B.Mask" "B.Paste")
			(net "GND")
		)
	)
	(footprint ""
		(layer "B.Cu")
		(at 205.307438 -403.804882 -90)
		(property "Reference" "PR3911"
			(at 0 0 90)
			(layer "B.SilkS")
			(hide yes)
			(effects
				(font
					(size 1.27 1.27)
				)
				(justify mirror)
			)
		)
		(property "Value" ""
			(at 0 0 90)
			(layer "B.Fab")
			(effects
				(font
					(size 1.27 1.27)
				)
				(justify mirror)
			)
		)
		(duplicate_pad_numbers_are_jumpers no)
		(fp_line
			(start -0.7874 0.4064)
			(end 0.7874 0.4064)
			(stroke
				(width 0.1524)
				(type default)
			)
			(layer "B.SilkS")
		)
		(fp_line
			(start 0.7874 0.4064)
			(end 0.7874 -0.4064)
			(stroke
				(width 0.1524)
				(type default)
			)
			(layer "B.SilkS")
		)
		(fp_line
			(start -0.7874 -0.4064)
			(end -0.7874 0.4064)
			(stroke
				(width 0.1524)
				(type default)
			)
			(layer "B.SilkS")
		)
		(fp_line
			(start 0.7874 -0.4064)
			(end -0.7874 -0.4064)
			(stroke
				(width 0.1524)
				(type default)
			)
			(layer "B.SilkS")
		)
		(fp_line
			(start -0.67945 0.3048)
			(end -0.120396 0.3048)
			(stroke
				(width 0.1)
				(type default)
			)
			(layer "B.Fab")
		)
		(fp_line
			(start -0.120396 0.3048)
			(end -0.120396 0.2794)
			(stroke
				(width 0.1)
				(type default)
			)
			(layer "B.Fab")
		)
		(fp_line
			(start 0.12065 0.3048)
			(end 0.67945 0.3048)
			(stroke
				(width 0.1)
				(type default)
			)
			(layer "B.Fab")
		)
		(fp_line
			(start 0.67945 0.3048)
			(end 0.67945 -0.305054)
			(stroke
				(width 0.1)
				(type default)
			)
			(layer "B.Fab")
		)
		(fp_line
			(start -0.120396 0.2794)
			(end 0.12065 0.2794)
			(stroke
				(width 0.1)
				(type default)
			)
			(layer "B.Fab")
		)
		(fp_line
			(start 0.12065 0.2794)
			(end 0.12065 0.3048)
			(stroke
				(width 0.1)
				(type default)
			)
			(layer "B.Fab")
		)
		(fp_line
			(start -0.12065 -0.2794)
			(end -0.12065 -0.3048)
			(stroke
				(width 0.1)
				(type default)
			)
			(layer "B.Fab")
		)
		(fp_line
			(start 0.12065 -0.2794)
			(end -0.12065 -0.2794)
			(stroke
				(width 0.1)
				(type default)
			)
			(layer "B.Fab")
		)
		(fp_line
			(start -0.67945 -0.3048)
			(end -0.67945 0.3048)
			(stroke
				(width 0.1)
				(type default)
			)
			(layer "B.Fab")
		)
		(fp_line
			(start -0.12065 -0.3048)
			(end -0.67945 -0.3048)
			(stroke
				(width 0.1)
				(type default)
			)
			(layer "B.Fab")
		)
		(fp_line
			(start 0.12065 -0.305054)
			(end 0.12065 -0.2794)
			(stroke
				(width 0.1)
				(type default)
			)
			(layer "B.Fab")
		)
		(fp_line
			(start 0.67945 -0.305054)
			(end 0.12065 -0.305054)
			(stroke
				(width 0.1)
				(type default)
			)
			(layer "B.Fab")
		)
		(pad "1" smd circle
			(at 0.40005 0 90)
			(size 0 0)
			(layers "B.Cu" "B.Mask" "B.Paste")
			(net "HSC_VDD_R_2")
		)
		(pad "2" smd circle
			(at -0.40005 0 90)
			(size 0 0)
			(layers "B.Cu" "B.Mask" "B.Paste")
			(net "HSC_VDD")
		)
	)
	(footprint ""
		(layer "B.Cu")
		(at 178.50866 -13.759688 90)
		(property "Reference" "R1386"
			(at 0 0 90)
			(layer "B.SilkS")
			(hide yes)
			(effects
				(font
					(size 1.27 1.27)
				)
				(justify mirror)
			)
		)
		(property "Value" ""
			(at 0 0 90)
			(layer "B.Fab")
			(effects
				(font
					(size 1.27 1.27)
				)
				(justify mirror)
			)
		)
		(duplicate_pad_numbers_are_jumpers no)
		(fp_line
			(start 0.7874 -0.4064)
			(end -0.7874 -0.4064)
			(stroke
				(width 0.1524)
				(type default)
			)
			(layer "B.SilkS")
		)
		(fp_line
			(start -0.7874 -0.4064)
			(end -0.7874 0.4064)
			(stroke
				(width 0.1524)
				(type default)
			)
			(layer "B.SilkS")
		)
		(fp_line
			(start 0.7874 0.4064)
			(end 0.7874 -0.4064)
			(stroke
				(width 0.1524)
				(type default)
			)
			(layer "B.SilkS")
		)
		(fp_line
			(start -0.7874 0.4064)
			(end 0.7874 0.4064)
			(stroke
				(width 0.1524)
				(type default)
			)
			(layer "B.SilkS")
		)
		(fp_line
			(start 0.67945 -0.305054)
			(end 0.12065 -0.305054)
			(stroke
				(width 0.1)
				(type default)
			)
			(layer "B.Fab")
		)
		(fp_line
			(start 0.12065 -0.305054)
			(end 0.12065 -0.2794)
			(stroke
				(width 0.1)
				(type default)
			)
			(layer "B.Fab")
		)
		(fp_line
			(start -0.12065 -0.3048)
			(end -0.67945 -0.3048)
			(stroke
				(width 0.1)
				(type default)
			)
			(layer "B.Fab")
		)
		(fp_line
			(start -0.67945 -0.3048)
			(end -0.67945 0.3048)
			(stroke
				(width 0.1)
				(type default)
			)
			(layer "B.Fab")
		)
		(fp_line
			(start 0.12065 -0.2794)
			(end -0.12065 -0.2794)
			(stroke
				(width 0.1)
				(type default)
			)
			(layer "B.Fab")
		)
		(fp_line
			(start -0.12065 -0.2794)
			(end -0.12065 -0.3048)
			(stroke
				(width 0.1)
				(type default)
			)
			(layer "B.Fab")
		)
		(fp_line
			(start 0.12065 0.2794)
			(end 0.12065 0.3048)
			(stroke
				(width 0.1)
				(type default)
			)
			(layer "B.Fab")
		)
		(fp_line
			(start -0.120396 0.2794)
			(end 0.12065 0.2794)
			(stroke
				(width 0.1)
				(type default)
			)
			(layer "B.Fab")
		)
		(fp_line
			(start 0.67945 0.3048)
			(end 0.67945 -0.305054)
			(stroke
				(width 0.1)
				(type default)
			)
			(layer "B.Fab")
		)
		(fp_line
			(start 0.12065 0.3048)
			(end 0.67945 0.3048)
			(stroke
				(width 0.1)
				(type default)
			)
			(layer "B.Fab")
		)
		(fp_line
			(start -0.120396 0.3048)
			(end -0.120396 0.2794)
			(stroke
				(width 0.1)
				(type default)
			)
			(layer "B.Fab")
		)
		(fp_line
			(start -0.67945 0.3048)
			(end -0.120396 0.3048)
			(stroke
				(width 0.1)
				(type default)
			)
			(layer "B.Fab")
		)
		(pad "1" smd circle
			(at 0.40005 0 270)
			(size 0 0)
			(layers "B.Cu" "B.Mask" "B.Paste")
			(net "SMB_SML1_PMBUS_3V3AUX_PCH_SCL")
		)
		(pad "2" smd circle
			(at -0.40005 0 270)
			(size 0 0)
			(layers "B.Cu" "B.Mask" "B.Paste")
			(net "P3V3_AUX")
		)
	)
	(footprint ""
		(layer "B.Cu")
		(at 312.443622 -35.804348)
		(property "Reference" "R1657"
			(at 0 0 0)
			(layer "B.SilkS")
			(hide yes)
			(effects
				(font
					(size 1.27 1.27)
				)
				(justify mirror)
			)
		)
		(property "Value" ""
			(at 0 0 0)
			(layer "B.Fab")
			(effects
				(font
					(size 1.27 1.27)
				)
				(justify mirror)
			)
		)
		(duplicate_pad_numbers_are_jumpers no)
		(fp_line
			(start -0.7874 -0.4064)
			(end -0.7874 0.4064)
			(stroke
				(width 0.1524)
				(type default)
			)
			(layer "B.SilkS")
		)
		(fp_line
			(start -0.7874 0.4064)
			(end 0.7874 0.4064)
			(stroke
				(width 0.1524)
				(type default)
			)
			(layer "B.SilkS")
		)
		(fp_line
			(start 0.7874 -0.4064)
			(end -0.7874 -0.4064)
			(stroke
				(width 0.1524)
				(type default)
			)
			(layer "B.SilkS")
		)
		(fp_line
			(start 0.7874 0.4064)
			(end 0.7874 -0.4064)
			(stroke
				(width 0.1524)
				(type default)
			)
			(layer "B.SilkS")
		)
		(fp_line
			(start -0.67945 -0.3048)
			(end -0.67945 0.3048)
			(stroke
				(width 0.1)
				(type default)
			)
			(layer "B.Fab")
		)
		(fp_line
			(start -0.67945 0.3048)
			(end -0.120396 0.3048)
			(stroke
				(width 0.1)
				(type default)
			)
			(layer "B.Fab")
		)
		(fp_line
			(start -0.12065 -0.3048)
			(end -0.67945 -0.3048)
			(stroke
				(width 0.1)
				(type default)
			)
			(layer "B.Fab")
		)
		(fp_line
			(start -0.12065 -0.2794)
			(end -0.12065 -0.3048)
			(stroke
				(width 0.1)
				(type default)
			)
			(layer "B.Fab")
		)
		(fp_line
			(start -0.120396 0.2794)
			(end 0.12065 0.2794)
			(stroke
				(width 0.1)
				(type default)
			)
			(layer "B.Fab")
		)
		(fp_line
			(start -0.120396 0.3048)
			(end -0.120396 0.2794)
			(stroke
				(width 0.1)
				(type default)
			)
			(layer "B.Fab")
		)
		(fp_line
			(start 0.12065 -0.305054)
			(end 0.12065 -0.2794)
			(stroke
				(width 0.1)
				(type default)
			)
			(layer "B.Fab")
		)
		(fp_line
			(start 0.12065 -0.2794)
			(end -0.12065 -0.2794)
			(stroke
				(width 0.1)
				(type default)
			)
			(layer "B.Fab")
		)
		(fp_line
			(start 0.12065 0.2794)
			(end 0.12065 0.3048)
			(stroke
				(width 0.1)
				(type default)
			)
			(layer "B.Fab")
		)
		(fp_line
			(start 0.12065 0.3048)
			(end 0.67945 0.3048)
			(stroke
				(width 0.1)
				(type default)
			)
			(layer "B.Fab")
		)
		(fp_line
			(start 0.67945 -0.305054)
			(end 0.12065 -0.305054)
			(stroke
				(width 0.1)
				(type default)
			)
			(layer "B.Fab")
		)
		(fp_line
			(start 0.67945 0.3048)
			(end 0.67945 -0.305054)
			(stroke
				(width 0.1)
				(type default)
			)
			(layer "B.Fab")
		)
		(pad "1" smd circle
			(at 0.40005 0 180)
			(size 0 0)
			(layers "B.Cu" "B.Mask" "B.Paste")
			(net "IRQ_SML1_PMBUS_ALERT_N")
		)
		(pad "2" smd circle
			(at -0.40005 0 180)
			(size 0 0)
			(layers "B.Cu" "B.Mask" "B.Paste")
			(net "IRQ_SML1_PMBUS_BMC_ALERT_N")
		)
	)
	(footprint ""
		(layer "B.Cu")
		(at 26.7716 -162.829748 -90)
		(property "Reference" "PR4254"
			(at 0 0 90)
			(layer "B.SilkS")
			(hide yes)
			(effects
				(font
					(size 1.27 1.27)
				)
				(justify mirror)
			)
		)
		(property "Value" ""
			(at 0 0 90)
			(layer "B.Fab")
			(effects
				(font
					(size 1.27 1.27)
				)
				(justify mirror)
			)
		)
		(duplicate_pad_numbers_are_jumpers no)
		(fp_line
			(start -0.7874 0.4064)
			(end 0.7874 0.4064)
			(stroke
				(width 0.1524)
				(type default)
			)
			(layer "B.SilkS")
		)
		(fp_line
			(start 0.7874 0.4064)
			(end 0.7874 -0.4064)
			(stroke
				(width 0.1524)
				(type default)
			)
			(layer "B.SilkS")
		)
		(fp_line
			(start -0.7874 -0.4064)
			(end -0.7874 0.4064)
			(stroke
				(width 0.1524)
				(type default)
			)
			(layer "B.SilkS")
		)
		(fp_line
			(start 0.7874 -0.4064)
			(end -0.7874 -0.4064)
			(stroke
				(width 0.1524)
				(type default)
			)
			(layer "B.SilkS")
		)
		(fp_line
			(start -0.67945 0.3048)
			(end -0.120396 0.3048)
			(stroke
				(width 0.1)
				(type default)
			)
			(layer "B.Fab")
		)
		(fp_line
			(start -0.120396 0.3048)
			(end -0.120396 0.2794)
			(stroke
				(width 0.1)
				(type default)
			)
			(layer "B.Fab")
		)
		(fp_line
			(start 0.12065 0.3048)
			(end 0.67945 0.3048)
			(stroke
				(width 0.1)
				(type default)
			)
			(layer "B.Fab")
		)
		(fp_line
			(start 0.67945 0.3048)
			(end 0.67945 -0.305054)
			(stroke
				(width 0.1)
				(type default)
			)
			(layer "B.Fab")
		)
		(fp_line
			(start -0.120396 0.2794)
			(end 0.12065 0.2794)
			(stroke
				(width 0.1)
				(type default)
			)
			(layer "B.Fab")
		)
		(fp_line
			(start 0.12065 0.2794)
			(end 0.12065 0.3048)
			(stroke
				(width 0.1)
				(type default)
			)
			(layer "B.Fab")
		)
		(fp_line
			(start -0.12065 -0.2794)
			(end -0.12065 -0.3048)
			(stroke
				(width 0.1)
				(type default)
			)
			(layer "B.Fab")
		)
		(fp_line
			(start 0.12065 -0.2794)
			(end -0.12065 -0.2794)
			(stroke
				(width 0.1)
				(type default)
			)
			(layer "B.Fab")
		)
		(fp_line
			(start -0.67945 -0.3048)
			(end -0.67945 0.3048)
			(stroke
				(width 0.1)
				(type default)
			)
			(layer "B.Fab")
		)
		(fp_line
			(start -0.12065 -0.3048)
			(end -0.67945 -0.3048)
			(stroke
				(width 0.1)
				(type default)
			)
			(layer "B.Fab")
		)
		(fp_line
			(start 0.12065 -0.305054)
			(end 0.12065 -0.2794)
			(stroke
				(width 0.1)
				(type default)
			)
			(layer "B.Fab")
		)
		(fp_line
			(start 0.67945 -0.305054)
			(end 0.12065 -0.305054)
			(stroke
				(width 0.1)
				(type default)
			)
			(layer "B.Fab")
		)
		(pad "1" smd circle
			(at 0.40005 0 90)
			(size 0 0)
			(layers "B.Cu" "B.Mask" "B.Paste")
			(net "NC_PVCCD_HV_CPU1_ACSP5")
		)
		(pad "2" smd circle
			(at -0.40005 0 90)
			(size 0 0)
			(layers "B.Cu" "B.Mask" "B.Paste")
			(net "GND")
		)
	)
	(footprint ""
		(layer "B.Cu")
		(at 77.142594 -46.044866)
		(property "Reference" "R3570"
			(at 0 0 0)
			(layer "B.SilkS")
			(hide yes)
			(effects
				(font
					(size 1.27 1.27)
				)
				(justify mirror)
			)
		)
		(property "Value" ""
			(at 0 0 0)
			(layer "B.Fab")
			(effects
				(font
					(size 1.27 1.27)
				)
				(justify mirror)
			)
		)
		(duplicate_pad_numbers_are_jumpers no)
		(fp_line
			(start -0.7874 -0.4064)
			(end -0.7874 0.4064)
			(stroke
				(width 0.1524)
				(type default)
			)
			(layer "B.SilkS")
		)
		(fp_line
			(start -0.7874 0.4064)
			(end 0.7874 0.4064)
			(stroke
				(width 0.1524)
				(type default)
			)
			(layer "B.SilkS")
		)
		(fp_line
			(start 0.7874 -0.4064)
			(end -0.7874 -0.4064)
			(stroke
				(width 0.1524)
				(type default)
			)
			(layer "B.SilkS")
		)
		(fp_line
			(start 0.7874 0.4064)
			(end 0.7874 -0.4064)
			(stroke
				(width 0.1524)
				(type default)
			)
			(layer "B.SilkS")
		)
		(fp_line
			(start -0.67945 -0.3048)
			(end -0.67945 0.3048)
			(stroke
				(width 0.1)
				(type default)
			)
			(layer "B.Fab")
		)
		(fp_line
			(start -0.67945 0.3048)
			(end -0.120396 0.3048)
			(stroke
				(width 0.1)
				(type default)
			)
			(layer "B.Fab")
		)
		(fp_line
			(start -0.12065 -0.3048)
			(end -0.67945 -0.3048)
			(stroke
				(width 0.1)
				(type default)
			)
			(layer "B.Fab")
		)
		(fp_line
			(start -0.12065 -0.2794)
			(end -0.12065 -0.3048)
			(stroke
				(width 0.1)
				(type default)
			)
			(layer "B.Fab")
		)
		(fp_line
			(start -0.120396 0.2794)
			(end 0.12065 0.2794)
			(stroke
				(width 0.1)
				(type default)
			)
			(layer "B.Fab")
		)
		(fp_line
			(start -0.120396 0.3048)
			(end -0.120396 0.2794)
			(stroke
				(width 0.1)
				(type default)
			)
			(layer "B.Fab")
		)
		(fp_line
			(start 0.12065 -0.305054)
			(end 0.12065 -0.2794)
			(stroke
				(width 0.1)
				(type default)
			)
			(layer "B.Fab")
		)
		(fp_line
			(start 0.12065 -0.2794)
			(end -0.12065 -0.2794)
			(stroke
				(width 0.1)
				(type default)
			)
			(layer "B.Fab")
		)
		(fp_line
			(start 0.12065 0.2794)
			(end 0.12065 0.3048)
			(stroke
				(width 0.1)
				(type default)
			)
			(layer "B.Fab")
		)
		(fp_line
			(start 0.12065 0.3048)
			(end 0.67945 0.3048)
			(stroke
				(width 0.1)
				(type default)
			)
			(layer "B.Fab")
		)
		(fp_line
			(start 0.67945 -0.305054)
			(end 0.12065 -0.305054)
			(stroke
				(width 0.1)
				(type default)
			)
			(layer "B.Fab")
		)
		(fp_line
			(start 0.67945 0.3048)
			(end 0.67945 -0.305054)
			(stroke
				(width 0.1)
				(type default)
			)
			(layer "B.Fab")
		)
		(pad "1" smd circle
			(at 0.40005 0 180)
			(size 0 0)
			(layers "B.Cu" "B.Mask" "B.Paste")
			(net "P3V3_OCP_V3_2_R")
		)
		(pad "2" smd circle
			(at -0.40005 0 180)
			(size 0 0)
			(layers "B.Cu" "B.Mask" "B.Paste")
			(net "VSENSE_P12V_INA230_3_INP")
		)
	)
)
